FILE_TYPE = CONNECTIVITY;
{Allegro Design Entry HDL 17.4-2019 S026 (4007227) 1/17/2022}
"PAGE_NUMBER" = 363;
0"NC";
1"P3V3_AUX\g";
2"GND\g";
3"GND\g";
4"GND\g";
5"P3V3_AUX\g";
6"P3V3_AUX\g";
7"GND\g";
8"FM_AC_PWR_BTN_PDB_N";
9"FM_FAN_PWR_EN_R";
10"GND\g";
11"RST_SMB_SWITCH_R_N";
12"FM_GPU_HSC_EN_BUF_R1";
13"P12V_PSU\g";
14"GND\g";
15"SMB_FAN_3V3AUX_BUF_R_SCL";
16"PDB_PRSNT_R_N";
17"FM_GPU_HSC_EN_BUF";
18"HPDB_HSC_PWRGD_R";
19"PDB_PRSNT_N";
20"FM_FAN_PWR_EN";
21"SMB_FAN_3V3AUX_BUF_R_SDA";
22"HPDB_HSC_PWRGD";
23"PDB_PRSNT_N";
24"HPDB_HSC_PWRGD_R";
25"FM_GPU_HSC_EN_BUF_R1";
26"FM_FAN_PWR_EN_R";
27"FM_AC_PWR_BTN_R_N";
28"FM_PDB_BUF_EN_R1";
29"FM_PDB_BUF_EN_R1_N";
30"FM_PDB_BUF_EN_R_N";
31"FM_AC_PWR_BTN_PDB_N";
32"PWRGD_P3V3_AUX_PDB_BUF";
33"P3V3_PDB_AUX_ADC";
34"TP_J45_A1";
35"RST_SMB_SWITCH_R_N";
36"RST_SMB_SWITCH_N";
37"SMB_FAN_3V3AUX_BUF_R_SDA";
38"SMB_FAN_3V3AUX_BUF_R_SCL";
39"SMB_FAN_3V3AUX_R_SDA";
40"SMB_FAN_3V3AUX_SCL";
41"SMB_FAN_3V3AUX_SDA";
42"SMB_FAN_3V3AUX_R_SCL";
43"MB_PDB_SMB9_R_EN";
44"SMB_FAN_3V3AUX_BUF_SCL";
45"SMB_FAN_3V3AUX_BUF_SDA";
46"P3V3_AUX\g";
47"P3V3_AUX\g";
%"UNIVERSAL_POWER"
"1","(-2875,475)","0","pure_quanta_power","I369";
;
HDL_POWER"P12V_PSU"
CDS_LIB"pure_quanta_power";
"A"13;
%"UNIVERSAL_GND"
"1","(-4375,-1200)","0","pure_quanta_power","I370";
;
CDS_LIB"pure_quanta_power"
HDL_POWER"GND";
"A"14;
%"Q_RES"
"1","(-2150,725)","0","pure_quanta","I387";
;
LOCATION"R2802"
$SEC"1"
CDS_SEC"1"
MATERIAL"CHIP"
VALUE"0"
TOLERANCE"5%"
CDS_LIB"pure_quanta"
PACK_TYPE"0402LF"
WATTAGE"1/16W"
PART_NUMBER"CS00002JB13"
LOCATION"R2802";
"B"
$PN"2"22;
"A"
$PN"1"18;
%"Q_RES"
"1","(-2150,675)","0","pure_quanta","I388";
;
LOCATION"R2803"
$SEC"1"
CDS_SEC"1"
VALUE"0"
TOLERANCE"5%"
MATERIAL"CHIP"
CDS_LIB"pure_quanta"
WATTAGE"1/16W"
PACK_TYPE"0402LF"
PART_NUMBER"CS00002JB13"
LOCATION"R2803";
"B"
$PN"2"20;
"A"
$PN"1"26;
%"MOSFET_NCH_GDS_ESD_PROTECTED"
"1","(-6000,-2650)","0","pure_quanta","I392";
;
LOCATION"U190"
$SEC"1"
CDS_SEC"1"
PART_TYPE"SMLF"
MATERIAL"IC"
VALUE"2N7002K"
CDS_LIB"pure_quanta"
NEEDS_NO_SIZE"TRUE"
CDS_LMAN_SYM_OUTLINE"-125,150,125,-150"
PART_NUMBER"BAM70020002";
"S"
$PN"S"2;
"G"
$PN"G"29;
"D"
$PN"D"28;
%"Q_RES"
"1","(-6875,-2650)","0","pure_quanta","I394";
;
LOCATION"R2793"
$SEC"1"
CDS_SEC"1"
MATERIAL"CHIP"
VALUE"0"
TOLERANCE"5%"
PACK_TYPE"0402LF"
WATTAGE"1/16W"
CDS_LIB"pure_quanta"
PART_NUMBER"CS00002JB13"
LOCATION"R2793";
"B"
$PN"2"29;
"A"
$PN"1"30;
%"UNIVERSAL_POWER"
"1","(-5975,-1775)","0","pure_quanta_power","I395";
;
HDL_POWER"P3V3_AUX"
CDS_LIB"pure_quanta_power";
"A"1;
%"Q_RES"
"2","(-5975,-2050)","0","pure_quanta","I396";
;
LOCATION"R2794"
$SEC"1"
CDS_SEC"1"
PACK_TYPE"0402LF"
WATTAGE"1/16W"
TOLERANCE"5%"
VALUE"4.7K"
MATERIAL"CHIP"
CDS_LIB"pure_quanta"
PART_NUMBER"CS24702JB10";
"A"
$PN"1"1;
"B"
$PN"2"28;
%"UNIVERSAL_GND"
"1","(-5975,-3100)","0","pure_quanta_power","I397";
;
CDS_LIB"pure_quanta_power"
HDL_POWER"GND";
"A"2;
%"LTC4307CMS8"
"1","(-3100,-3400)","0","pure_quanta","I398";
;
LOCATION"U192"
$SEC"1"
CDS_SEC"1"
PART_TYPE"SMLF"
MATERIAL"IC"
VALUE"LTC4307CMS8"
NEEDS_NO_SIZE"TRUE"
CDS_LIB"pure_quanta"
PART_NUMBER"AL004307000";
"READY"
$PN"5"0;
"SDA_OUT"
$PN"7"45;
"SCL_OUT"
$PN"2"44;
"VCC"
$PN"8"47;
"GND"
$PN"4"3;
"SDA_IN"
$PN"6"39;
"SCL_IN"
$PN"3"42;
"ENABLE"
$PN"1"43;
%"UNIVERSAL_GND"
"1","(-3525,-3650)","0","pure_quanta_power","I405";
;
CDS_LIB"pure_quanta_power"
HDL_POWER"GND";
"A"3;
%"Q_CAP"
"1","(-2250,-2825)","2","pure_quanta","I412";
;
LOCATION"C1751"
$SEC"1"
CDS_SEC"1"
MATERIAL"X7R"
VOLTAGE"25V"
TOLERANCE"10%"
VALUE"0.1UF"
PACK_TYPE"0402"
CDS_LIB"pure_quanta"
PART_NUMBER"CH4104K1B00";
"B"
$PN"2"4;
"A"
$PN"1"47;
%"UNIVERSAL_GND"
"1","(-2250,-3075)","0","pure_quanta_power","I413";
;
CDS_LIB"pure_quanta_power"
HDL_POWER"GND";
"A"4;
%"UNIVERSAL_POWER"
"1","(-2600,-2550)","0","pure_quanta_power","I414";
;
HDL_POWER"P3V3_AUX"
CDS_LIB"pure_quanta_power";
"A"47;
%"Q_RES"
"1","(-4650,-3250)","0","pure_quanta","I420";
;
LOCATION"R2796"
$SEC"1"
CDS_SEC"1"
MATERIAL"CHIP"
TOLERANCE"5%"
VALUE"0"
CDS_LIB"pure_quanta"
PACK_TYPE"0402LF"
WATTAGE"1/16W"
PART_NUMBER"CS00002JB13"
LOCATION"R2796";
"B"
$PN"2"43;
"A"
$PN"1"28;
%"Q_RES"
"1","(-1075,-3350)","0","pure_quanta","I425";
;
LOCATION"R2811"
$SEC"1"
CDS_SEC"1"
VALUE"33.2"
MATERIAL"CHIP"
TOLERANCE"1%"
CDS_LIB"pure_quanta"
WATTAGE"1/16W"
PACK_TYPE"0402LF"
PART_NUMBER"CS03322FB03";
"B"
$PN"2"38;
"A"
$PN"1"44;
%"Q_RES"
"1","(-1075,-3450)","0","pure_quanta","I426";
;
LOCATION"R2812"
$SEC"1"
CDS_SEC"1"
VALUE"33.2"
MATERIAL"CHIP"
TOLERANCE"1%"
WATTAGE"1/16W"
PACK_TYPE"0402LF"
CDS_LIB"pure_quanta"
PART_NUMBER"CS03322FB03";
"B"
$PN"2"37;
"A"
$PN"1"45;
%"Q_RES"
"1","(-3125,-3800)","0","pure_quanta","I429";
;
LOCATION"R2800"
$SEC"1"
CDS_SEC"1"
MATERIAL"EMPTY"
VALUE"0"
WATTAGE"1/16W"
TOLERANCE"5%"
PACK_TYPE"0402LF"
CDS_LIB"pure_quanta"
PART_NUMBER"CS00002JB13";
"B"
$PN"2"44;
"A"
$PN"1"42;
%"Q_RES"
"1","(-3125,-3875)","0","pure_quanta","I430";
;
LOCATION"R2801"
$SEC"1"
CDS_SEC"1"
VALUE"0"
TOLERANCE"5%"
MATERIAL"EMPTY"
WATTAGE"1/16W"
PACK_TYPE"0402LF"
CDS_LIB"pure_quanta"
PART_NUMBER"CS00002JB13";
"B"
$PN"2"45;
"A"
$PN"1"39;
%"Q_RES"
"2","(-1800,-2900)","0","pure_quanta","I436";
;
LOCATION"R2805"
$SEC"1"
CDS_SEC"1"
MATERIAL"EMPTY"
PACK_TYPE"0402LF"
WATTAGE"1/16W"
TOLERANCE"5%"
VALUE"4.7K"
CDS_LIB"pure_quanta"
PART_NUMBER"CS24702JB10";
"A"
$PN"1"46;
"B"
$PN"2"44;
%"UNIVERSAL_POWER"
"1","(-1800,-2600)","0","pure_quanta_power","I437";
;
HDL_POWER"P3V3_AUX"
CDS_LIB"pure_quanta_power";
"A"46;
%"Q_RES"
"2","(-1550,-2925)","0","pure_quanta","I438";
;
LOCATION"R2807"
$SEC"1"
CDS_SEC"1"
MATERIAL"EMPTY"
WATTAGE"1/16W"
TOLERANCE"5%"
PACK_TYPE"0402LF"
VALUE"4.7K"
CDS_LIB"pure_quanta"
PART_NUMBER"CS24702JB10";
"A"
$PN"1"46;
"B"
$PN"2"45;
%"Q_RES"
"1","(-2150,625)","0","pure_quanta","I440";
;
LOCATION"R2906"
$SEC"1"
CDS_SEC"1"
TOLERANCE"5%"
VALUE"0"
MATERIAL"CHIP"
CDS_LIB"pure_quanta"
WATTAGE"1/16W"
PACK_TYPE"0402LF"
PART_NUMBER"CS00002JB13";
"B"
$PN"2"17;
"A"
$PN"1"25;
%"Q_RES"
"1","(-5750,675)","0","pure_quanta","I441";
;
LOCATION"R2905"
$SEC"1"
CDS_SEC"1"
MATERIAL"CHIP"
TOLERANCE"5%"
VALUE"0"
CDS_LIB"pure_quanta"
PACK_TYPE"0402LF"
WATTAGE"1/16W"
PART_NUMBER"CS00002JB13";
"B"
$PN"2"35;
"A"
$PN"1"36;
%"Q_CAP"
"2","(200,100)","0","pure_quanta","I452";
;
LOCATION"C74"
$SEC"1"
CDS_SEC"1"
VALUE"0.1UF"
MATERIAL"EMPTY"
CDS_LIB"pure_quanta"
PACK_TYPE"0402"
TOLERANCE"10%"
VOLTAGE"25V"
PART_NUMBER"CH4104K1B00";
"A"
$PN"1"11;
"B"
$PN"2"10;
%"Q_CAP"
"2","(200,-50)","0","pure_quanta","I453";
;
LOCATION"C64"
$SEC"1"
CDS_SEC"1"
VALUE"0.1UF"
MATERIAL"EMPTY"
CDS_LIB"pure_quanta"
PACK_TYPE"0402"
TOLERANCE"10%"
VOLTAGE"25V"
PART_NUMBER"CH4104K1B00";
"A"
$PN"1"23;
"B"
$PN"2"10;
%"Q_CAP"
"2","(200,-200)","0","pure_quanta","I454";
;
LOCATION"C65"
$SEC"1"
CDS_SEC"1"
MATERIAL"EMPTY"
VALUE"0.1UF"
CDS_LIB"pure_quanta"
PACK_TYPE"0402"
TOLERANCE"10%"
VOLTAGE"25V"
PART_NUMBER"CH4104K1B00";
"A"
$PN"1"24;
"B"
$PN"2"10;
%"Q_CAP"
"2","(200,-350)","0","pure_quanta","I455";
;
LOCATION"C66"
$SEC"1"
CDS_SEC"1"
MATERIAL"EMPTY"
VALUE"0.1UF"
CDS_LIB"pure_quanta"
PACK_TYPE"0402"
TOLERANCE"10%"
VOLTAGE"25V"
PART_NUMBER"CH4104K1B00";
"A"
$PN"1"9;
"B"
$PN"2"10;
%"Q_CAP"
"2","(200,-500)","0","pure_quanta","I456";
;
LOCATION"C67"
$SEC"1"
CDS_SEC"1"
MATERIAL"EMPTY"
VALUE"0.1UF"
CDS_LIB"pure_quanta"
PACK_TYPE"0402"
TOLERANCE"10%"
VOLTAGE"25V"
PART_NUMBER"CH4104K1B00";
"A"
$PN"1"12;
"B"
$PN"2"10;
%"UNIVERSAL_GND"
"1","(650,-875)","0","pure_quanta_power","I462";
;
CDS_LIB"pure_quanta_power"
HDL_POWER"GND";
"A"10;
%"Q_RES"
"1","(-4650,-3350)","0","pure_quanta","I463";
;
LOCATION"R3113"
$SEC"1"
CDS_SEC"1"
VALUE"33.2"
TOLERANCE"1%"
MATERIAL"CHIP"
WATTAGE"1/16W"
PACK_TYPE"0402LF"
CDS_LIB"pure_quanta"
PART_NUMBER"CS03322FB03";
"B"
$PN"2"42;
"A"
$PN"1"40;
%"Q_RES"
"1","(-4650,-3450)","0","pure_quanta","I464";
;
LOCATION"R3114"
$SEC"1"
CDS_SEC"1"
TOLERANCE"1%"
MATERIAL"CHIP"
VALUE"33.2"
WATTAGE"1/16W"
PACK_TYPE"0402LF"
CDS_LIB"pure_quanta"
PART_NUMBER"CS03322FB03";
"B"
$PN"2"39;
"A"
$PN"1"41;
%"CONN60_101062636003K02LF"
"1","(-3750,-75)","0","pure_quanta","I466";
;
LOCATION"J45"
SEC"1"
VALUE"CONN60_10106263-6003K02LF"
PART_TYPE"THLF"
MATERIAL"IO"
CDS_LMAN_SYM_OUTLINE"-250,1000,250,-1000"
NEEDS_NO_SIZE"TRUE"
CDS_LIB"pure_quanta"
SEC_TYPE""
PART_NUMBER"DFHD60MR024";
"D3"
$PN"D3"19;
"C3"
$PN"C3"18;
"B3"
$PN"B3"14;
"A3"
$PN"A3"33;
"P6_8"
$PN"P6_8"13;
"P6_7"
$PN"P6_7"13;
"P6_6"
$PN"P6_6"13;
"P6_5"
$PN"P6_5"13;
"P6_4"
$PN"P6_4"13;
"P6_3"
$PN"P6_3"13;
"P6_2"
$PN"P6_2"13;
"P6_1"
$PN"P6_1"13;
"P3_8"
$PN"P3_8"14;
"P3_7"
$PN"P3_7"14;
"P3_6"
$PN"P3_6"14;
"P3_5"
$PN"P3_5"14;
"P3_4"
$PN"P3_4"14;
"P3_3"
$PN"P3_3"14;
"P3_2"
$PN"P3_2"14;
"P3_1"
$PN"P3_1"14;
"P5_8"
$PN"P5_8"13;
"P5_7"
$PN"P5_7"13;
"P5_6"
$PN"P5_6"13;
"P5_5"
$PN"P5_5"13;
"P5_4"
$PN"P5_4"13;
"P5_3"
$PN"P5_3"13;
"P5_2"
$PN"P5_2"13;
"P5_1"
$PN"P5_1"13;
"D1"
$PN"D1"26;
"C1"
$PN"C1"15;
"B1"
$PN"B1"35;
"A1"
$PN"A1"34;
"P4_8"
$PN"P4_8"13;
"P4_7"
$PN"P4_7"13;
"P4_6"
$PN"P4_6"13;
"P4_5"
$PN"P4_5"13;
"P4_4"
$PN"P4_4"13;
"P4_3"
$PN"P4_3"13;
"P4_2"
$PN"P4_2"13;
"P4_1"
$PN"P4_1"13;
"P2_8"
$PN"P2_8"14;
"P2_7"
$PN"P2_7"14;
"P2_6"
$PN"P2_6"14;
"P2_5"
$PN"P2_5"14;
"P2_4"
$PN"P2_4"14;
"P2_3"
$PN"P2_3"14;
"P2_2"
$PN"P2_2"14;
"P2_1"
$PN"P2_1"14;
"P1_8"
$PN"P1_8"14;
"P1_7"
$PN"P1_7"14;
"P1_6"
$PN"P1_6"14;
"P1_5"
$PN"P1_5"14;
"P1_4"
$PN"P1_4"14;
"P1_3"
$PN"P1_3"14;
"P1_2"
$PN"P1_2"14;
"P1_1"
$PN"P1_1"14;
"D2"
$PN"D2"25;
"C2"
$PN"C2"21;
"B2"
$PN"B2"32;
"A2"
$PN"A2"31;
%"Q_RES"
"1","(-5750,775)","0","pure_quanta","I467";
;
LOCATION"R8102"
$SEC"1"
CDS_SEC"1"
VALUE"0"
TOLERANCE"5%"
MATERIAL"CHIP"
PACK_TYPE"0402LF"
WATTAGE"1/16W"
CDS_LIB"pure_quanta"
PART_NUMBER"CS00002JB13";
"B"
$PN"2"31;
"A"
$PN"1"27;
%"Q_CAP"
"2","(200,-700)","0","pure_quanta","I469";
;
LOCATION"C8011"
$SEC"1"
CDS_SEC"1"
MATERIAL"EMPTY"
VALUE"0.1UF"
CDS_LIB"pure_quanta"
VOLTAGE"25V"
TOLERANCE"10%"
PACK_TYPE"0402"
PART_NUMBER"CH4104K1B00";
"A"
$PN"1"8;
"B"
$PN"2"10;
%"UNIVERSAL_POWER"
"1","(-1100,1325)","0","pure_quanta_power","I471";
;
HDL_POWER"P3V3_AUX"
CDS_LIB"pure_quanta_power";
"A"5;
%"Q_RES"
"2","(-1100,1050)","0","pure_quanta","I472";
;
LOCATION"R9000"
$SEC"1"
CDS_SEC"1"
MATERIAL"CHIP"
WATTAGE"1/16W"
PACK_TYPE"0402LF"
TOLERANCE"1%"
VALUE"1K"
CDS_LIB"pure_quanta"
PART_NUMBER"CS21002FB06";
"A"
$PN"1"5;
"B"
$PN"2"20;
%"UNIVERSAL_POWER"
"1","(-6275,-2050)","0","pure_quanta_power","I473";
;
HDL_POWER"P3V3_AUX"
CDS_LIB"pure_quanta_power";
"A"6;
%"Q_RES"
"2","(-6275,-2325)","2","pure_quanta","I475";
;
LOCATION"R2950"
$SEC"1"
CDS_SEC"1"
PACK_TYPE"0402LF"
MATERIAL"CHIP"
WATTAGE"1/16W"
TOLERANCE"1%"
VALUE"1K"
CDS_LIB"pure_quanta"
PART_NUMBER"CS21002FB06";
"A"
$PN"1"6;
"B"
$PN"2"29;
%"Q_RES"
"1","(-2150,575)","0","pure_quanta","I476";
;
LOCATION"R1526"
$SEC"1"
CDS_SEC"1"
MATERIAL"CHIP"
VALUE"0"
TOLERANCE"5%"
WATTAGE"1/16W"
PACK_TYPE"0402LF"
CDS_LIB"pure_quanta"
PART_NUMBER"CS00002JB13";
"B"
$PN"2"16;
"A"
$PN"1"19;
%"Q_CAP"
"1","(-1700,375)","2","pure_quanta","I478";
;
LOCATION"C1115"
$SEC"1"
CDS_SEC"1"
PACK_TYPE"C0805"
VALUE"22UF"
VOLTAGE"16V"
TOLERANCE"20%"
MATERIAL"EMPTY"
CDS_LIB"pure_quanta"
PART_NUMBER"CH6223MEA00";
"B"
$PN"2"7;
"A"
$PN"1"16;
%"UNIVERSAL_GND"
"1","(-1700,50)","0","pure_quanta_power","I479";
;
CDS_LIB"pure_quanta_power"
HDL_POWER"GND";
"A"7;
END.
